(kicad_pcb
	(version 20260206)
	(generator "pcbnew")
	(generator_version "10.0")
	(general
		(thickness 1.6)
		(legacy_teardrops no)
	)
	(paper "A4")
	(title_block
		(title "12092022_DA0F0TMDCD0_F0T_Management_Board_D_brd_V3_OCP.brd")
		(comment 1 "Grand Teton / footprints 1035-1040 of 1440")
	)
	(layers
		(0 "F.Cu" signal "TOP")
		(4 "In1.Cu" signal "GND")
		(6 "In2.Cu" signal "IN1")
		(8 "In3.Cu" signal "GND1")
		(10 "In4.Cu" signal "IN2")
		(12 "In5.Cu" signal "VCC")
		(14 "In6.Cu" signal "VCC1")
		(16 "In7.Cu" signal "IN3")
		(18 "In8.Cu" signal "GND2")
		(20 "In9.Cu" signal "IN4")
		(22 "In10.Cu" signal "GND3")
		(2 "B.Cu" signal "BOTTOM")
		(9 "F.Adhes" user "F.Adhesive")
		(11 "B.Adhes" user "B.Adhesive")
		(13 "F.Paste" user "Package Geometry/Pastemask Top")
		(15 "B.Paste" user "Package Geometry/Pastemask Bottom")
		(5 "F.SilkS" user "Ref Des/Silkscreen Top")
		(7 "B.SilkS" user "Ref Des/Silkscreen Bottom")
		(1 "F.Mask" user "Board Geometry/Soldermask Top")
		(3 "B.Mask" user "Board Geometry/Soldermask Bottom")
		(17 "Dwgs.User" user "User.Drawings")
		(19 "Cmts.User" user "User.Comments")
		(21 "Eco1.User" user "User.Eco1")
		(23 "Eco2.User" user "User.Eco2")
		(25 "Edge.Cuts" user "Board Geometry/Outline")
		(27 "Margin" user)
		(31 "F.CrtYd" user "Package Geometry/Place Bound Top")
		(29 "B.CrtYd" user "Package Geometry/Place Bound Bottom")
		(35 "F.Fab" user "Ref Des/Assembly Top")
		(33 "B.Fab" user "Ref Des/Assembly Bottom")
	)
	(footprint ""
		(layer "B.Cu")
		(at 69.85 -57.023)
		(property "Reference" "C113"
			(at 0 0 0)
			(layer "B.SilkS")
			(hide yes)
			(effects
				(font
					(size 1.27 1.27)
				)
				(justify mirror)
			)
		)
		(property "Value" ""
			(at 0 0 0)
			(layer "B.Fab")
			(effects
				(font
					(size 1.27 1.27)
				)
				(justify mirror)
			)
		)
		(duplicate_pad_numbers_are_jumpers no)
		(fp_line
			(start -1.2954 -0.5842)
			(end -1.2954 0.5842)
			(stroke
				(width 0.1524)
				(type default)
			)
			(layer "B.SilkS")
		)
		(fp_line
			(start -1.2954 0.5842)
			(end 1.2954 0.5842)
			(stroke
				(width 0.1524)
				(type default)
			)
			(layer "B.SilkS")
		)
		(fp_line
			(start 0 -0.5842)
			(end 0 0.5842)
			(stroke
				(width 0.1524)
				(type default)
			)
			(layer "B.SilkS")
		)
		(fp_line
			(start 1.2954 -0.5842)
			(end -1.2954 -0.5842)
			(stroke
				(width 0.1524)
				(type default)
			)
			(layer "B.SilkS")
		)
		(fp_line
			(start 1.2954 0.5842)
			(end 1.2954 -0.5842)
			(stroke
				(width 0.1524)
				(type default)
			)
			(layer "B.SilkS")
		)
		(fp_line
			(start -1.1938 -0.4064)
			(end -1.1938 0.4064)
			(stroke
				(width 0.1)
				(type default)
			)
			(layer "B.Fab")
		)
		(fp_line
			(start -1.1938 0.4064)
			(end -0.8636 0.4064)
			(stroke
				(width 0.1)
				(type default)
			)
			(layer "B.Fab")
		)
		(fp_line
			(start -0.8636 -0.4572)
			(end -0.8636 -0.4064)
			(stroke
				(width 0.1)
				(type default)
			)
			(layer "B.Fab")
		)
		(fp_line
			(start -0.8636 -0.4064)
			(end -1.1938 -0.4064)
			(stroke
				(width 0.1)
				(type default)
			)
			(layer "B.Fab")
		)
		(fp_line
			(start -0.8636 0.4064)
			(end -0.8636 0.4572)
			(stroke
				(width 0.1)
				(type default)
			)
			(layer "B.Fab")
		)
		(fp_line
			(start -0.8636 0.4572)
			(end 0.8636 0.4572)
			(stroke
				(width 0.1)
				(type default)
			)
			(layer "B.Fab")
		)
		(fp_line
			(start 0.8636 -0.4572)
			(end -0.8636 -0.4572)
			(stroke
				(width 0.1)
				(type default)
			)
			(layer "B.Fab")
		)
		(fp_line
			(start 0.8636 -0.4064)
			(end 0.8636 -0.4572)
			(stroke
				(width 0.1)
				(type default)
			)
			(layer "B.Fab")
		)
		(fp_line
			(start 0.8636 0.4064)
			(end 1.1938 0.4064)
			(stroke
				(width 0.1)
				(type default)
			)
			(layer "B.Fab")
		)
		(fp_line
			(start 0.8636 0.4572)
			(end 0.8636 0.4064)
			(stroke
				(width 0.1)
				(type default)
			)
			(layer "B.Fab")
		)
		(fp_line
			(start 1.1938 -0.4064)
			(end 0.8636 -0.4064)
			(stroke
				(width 0.1)
				(type default)
			)
			(layer "B.Fab")
		)
		(fp_line
			(start 1.1938 0.4064)
			(end 1.1938 -0.4064)
			(stroke
				(width 0.1)
				(type default)
			)
			(layer "B.Fab")
		)
		(pad "1" smd rect
			(at 0.7366 0 270)
			(size 0.7112 0.8128)
			(layers "B.Cu" "B.Mask" "B.Paste")
			(net "P1V0_AUX")
		)
		(pad "2" smd rect
			(at -0.7366 0 270)
			(size 0.7112 0.8128)
			(layers "B.Cu" "B.Mask" "B.Paste")
			(net "GND")
		)
	)
	(footprint ""
		(layer "B.Cu")
		(at 47.498 -34.671 90)
		(property "Reference" "R589"
			(at 0 0 90)
			(layer "B.SilkS")
			(hide yes)
			(effects
				(font
					(size 1.27 1.27)
				)
				(justify mirror)
			)
		)
		(property "Value" ""
			(at 0 0 90)
			(layer "B.Fab")
			(effects
				(font
					(size 1.27 1.27)
				)
				(justify mirror)
			)
		)
		(duplicate_pad_numbers_are_jumpers no)
		(fp_line
			(start 0.7874 -0.4064)
			(end -0.7874 -0.4064)
			(stroke
				(width 0.1524)
				(type default)
			)
			(layer "B.SilkS")
		)
		(fp_line
			(start -0.7874 -0.4064)
			(end -0.7874 0.4064)
			(stroke
				(width 0.1524)
				(type default)
			)
			(layer "B.SilkS")
		)
		(fp_line
			(start 0.7874 0.4064)
			(end 0.7874 -0.4064)
			(stroke
				(width 0.1524)
				(type default)
			)
			(layer "B.SilkS")
		)
		(fp_line
			(start -0.7874 0.4064)
			(end 0.7874 0.4064)
			(stroke
				(width 0.1524)
				(type default)
			)
			(layer "B.SilkS")
		)
		(fp_line
			(start 0.67945 -0.305054)
			(end 0.12065 -0.305054)
			(stroke
				(width 0.1)
				(type default)
			)
			(layer "B.Fab")
		)
		(fp_line
			(start 0.12065 -0.305054)
			(end 0.12065 -0.2794)
			(stroke
				(width 0.1)
				(type default)
			)
			(layer "B.Fab")
		)
		(fp_line
			(start -0.12065 -0.3048)
			(end -0.67945 -0.3048)
			(stroke
				(width 0.1)
				(type default)
			)
			(layer "B.Fab")
		)
		(fp_line
			(start -0.67945 -0.3048)
			(end -0.67945 0.3048)
			(stroke
				(width 0.1)
				(type default)
			)
			(layer "B.Fab")
		)
		(fp_line
			(start 0.12065 -0.2794)
			(end -0.12065 -0.2794)
			(stroke
				(width 0.1)
				(type default)
			)
			(layer "B.Fab")
		)
		(fp_line
			(start -0.12065 -0.2794)
			(end -0.12065 -0.3048)
			(stroke
				(width 0.1)
				(type default)
			)
			(layer "B.Fab")
		)
		(fp_line
			(start 0.12065 0.2794)
			(end 0.12065 0.3048)
			(stroke
				(width 0.1)
				(type default)
			)
			(layer "B.Fab")
		)
		(fp_line
			(start -0.120396 0.2794)
			(end 0.12065 0.2794)
			(stroke
				(width 0.1)
				(type default)
			)
			(layer "B.Fab")
		)
		(fp_line
			(start 0.67945 0.3048)
			(end 0.67945 -0.305054)
			(stroke
				(width 0.1)
				(type default)
			)
			(layer "B.Fab")
		)
		(fp_line
			(start 0.12065 0.3048)
			(end 0.67945 0.3048)
			(stroke
				(width 0.1)
				(type default)
			)
			(layer "B.Fab")
		)
		(fp_line
			(start -0.120396 0.3048)
			(end -0.120396 0.2794)
			(stroke
				(width 0.1)
				(type default)
			)
			(layer "B.Fab")
		)
		(fp_line
			(start -0.67945 0.3048)
			(end -0.120396 0.3048)
			(stroke
				(width 0.1)
				(type default)
			)
			(layer "B.Fab")
		)
		(pad "1" smd circle
			(at 0.40005 0 270)
			(size 0 0)
			(layers "B.Cu" "B.Mask" "B.Paste")
			(net "SMB_BMC_MM3_R_SCL")
		)
		(pad "2" smd circle
			(at -0.40005 0 270)
			(size 0 0)
			(layers "B.Cu" "B.Mask" "B.Paste")
			(net "SMB_BMC_MM3_SCL")
		)
	)
	(footprint ""
		(layer "B.Cu")
		(at 81.129886 -45.054012 180)
		(property "Reference" "R2"
			(at 0 0 0)
			(layer "B.SilkS")
			(hide yes)
			(effects
				(font
					(size 1.27 1.27)
				)
				(justify mirror)
			)
		)
		(property "Value" ""
			(at 0 0 0)
			(layer "B.Fab")
			(effects
				(font
					(size 1.27 1.27)
				)
				(justify mirror)
			)
		)
		(duplicate_pad_numbers_are_jumpers no)
		(fp_line
			(start 0.7874 0.4064)
			(end 0.7874 -0.4064)
			(stroke
				(width 0.1524)
				(type default)
			)
			(layer "B.SilkS")
		)
		(fp_line
			(start 0.7874 -0.4064)
			(end -0.7874 -0.4064)
			(stroke
				(width 0.1524)
				(type default)
			)
			(layer "B.SilkS")
		)
		(fp_line
			(start -0.7874 0.4064)
			(end 0.7874 0.4064)
			(stroke
				(width 0.1524)
				(type default)
			)
			(layer "B.SilkS")
		)
		(fp_line
			(start -0.7874 -0.4064)
			(end -0.7874 0.4064)
			(stroke
				(width 0.1524)
				(type default)
			)
			(layer "B.SilkS")
		)
		(fp_line
			(start 0.67945 0.3048)
			(end 0.67945 -0.305054)
			(stroke
				(width 0.1)
				(type default)
			)
			(layer "B.Fab")
		)
		(fp_line
			(start 0.67945 -0.305054)
			(end 0.12065 -0.305054)
			(stroke
				(width 0.1)
				(type default)
			)
			(layer "B.Fab")
		)
		(fp_line
			(start 0.12065 0.3048)
			(end 0.67945 0.3048)
			(stroke
				(width 0.1)
				(type default)
			)
			(layer "B.Fab")
		)
		(fp_line
			(start 0.12065 0.2794)
			(end 0.12065 0.3048)
			(stroke
				(width 0.1)
				(type default)
			)
			(layer "B.Fab")
		)
		(fp_line
			(start 0.12065 -0.2794)
			(end -0.12065 -0.2794)
			(stroke
				(width 0.1)
				(type default)
			)
			(layer "B.Fab")
		)
		(fp_line
			(start 0.12065 -0.305054)
			(end 0.12065 -0.2794)
			(stroke
				(width 0.1)
				(type default)
			)
			(layer "B.Fab")
		)
		(fp_line
			(start -0.120396 0.3048)
			(end -0.120396 0.2794)
			(stroke
				(width 0.1)
				(type default)
			)
			(layer "B.Fab")
		)
		(fp_line
			(start -0.120396 0.2794)
			(end 0.12065 0.2794)
			(stroke
				(width 0.1)
				(type default)
			)
			(layer "B.Fab")
		)
		(fp_line
			(start -0.12065 -0.2794)
			(end -0.12065 -0.3048)
			(stroke
				(width 0.1)
				(type default)
			)
			(layer "B.Fab")
		)
		(fp_line
			(start -0.12065 -0.3048)
			(end -0.67945 -0.3048)
			(stroke
				(width 0.1)
				(type default)
			)
			(layer "B.Fab")
		)
		(fp_line
			(start -0.67945 0.3048)
			(end -0.120396 0.3048)
			(stroke
				(width 0.1)
				(type default)
			)
			(layer "B.Fab")
		)
		(fp_line
			(start -0.67945 -0.3048)
			(end -0.67945 0.3048)
			(stroke
				(width 0.1)
				(type default)
			)
			(layer "B.Fab")
		)
		(pad "1" smd circle
			(at 0.40005 0)
			(size 0 0)
			(layers "B.Cu" "B.Mask" "B.Paste")
			(net "M_BMC_DDR4_BG1")
		)
		(pad "2" smd circle
			(at -0.40005 0)
			(size 0 0)
			(layers "B.Cu" "B.Mask" "B.Paste")
			(net "GND")
		)
	)
	(footprint ""
		(layer "B.Cu")
		(at 32.766 -91.821)
		(property "Reference" "R183"
			(at 0 0 0)
			(layer "B.SilkS")
			(hide yes)
			(effects
				(font
					(size 1.27 1.27)
				)
				(justify mirror)
			)
		)
		(property "Value" ""
			(at 0 0 0)
			(layer "B.Fab")
			(effects
				(font
					(size 1.27 1.27)
				)
				(justify mirror)
			)
		)
		(duplicate_pad_numbers_are_jumpers no)
		(fp_line
			(start -0.7874 -0.4064)
			(end -0.7874 0.4064)
			(stroke
				(width 0.1524)
				(type default)
			)
			(layer "B.SilkS")
		)
		(fp_line
			(start -0.7874 0.4064)
			(end 0.7874 0.4064)
			(stroke
				(width 0.1524)
				(type default)
			)
			(layer "B.SilkS")
		)
		(fp_line
			(start 0.7874 -0.4064)
			(end -0.7874 -0.4064)
			(stroke
				(width 0.1524)
				(type default)
			)
			(layer "B.SilkS")
		)
		(fp_line
			(start 0.7874 0.4064)
			(end 0.7874 -0.4064)
			(stroke
				(width 0.1524)
				(type default)
			)
			(layer "B.SilkS")
		)
		(fp_line
			(start -0.67945 -0.3048)
			(end -0.67945 0.3048)
			(stroke
				(width 0.1)
				(type default)
			)
			(layer "B.Fab")
		)
		(fp_line
			(start -0.67945 0.3048)
			(end -0.120396 0.3048)
			(stroke
				(width 0.1)
				(type default)
			)
			(layer "B.Fab")
		)
		(fp_line
			(start -0.12065 -0.3048)
			(end -0.67945 -0.3048)
			(stroke
				(width 0.1)
				(type default)
			)
			(layer "B.Fab")
		)
		(fp_line
			(start -0.12065 -0.2794)
			(end -0.12065 -0.3048)
			(stroke
				(width 0.1)
				(type default)
			)
			(layer "B.Fab")
		)
		(fp_line
			(start -0.120396 0.2794)
			(end 0.12065 0.2794)
			(stroke
				(width 0.1)
				(type default)
			)
			(layer "B.Fab")
		)
		(fp_line
			(start -0.120396 0.3048)
			(end -0.120396 0.2794)
			(stroke
				(width 0.1)
				(type default)
			)
			(layer "B.Fab")
		)
		(fp_line
			(start 0.12065 -0.305054)
			(end 0.12065 -0.2794)
			(stroke
				(width 0.1)
				(type default)
			)
			(layer "B.Fab")
		)
		(fp_line
			(start 0.12065 -0.2794)
			(end -0.12065 -0.2794)
			(stroke
				(width 0.1)
				(type default)
			)
			(layer "B.Fab")
		)
		(fp_line
			(start 0.12065 0.2794)
			(end 0.12065 0.3048)
			(stroke
				(width 0.1)
				(type default)
			)
			(layer "B.Fab")
		)
		(fp_line
			(start 0.12065 0.3048)
			(end 0.67945 0.3048)
			(stroke
				(width 0.1)
				(type default)
			)
			(layer "B.Fab")
		)
		(fp_line
			(start 0.67945 -0.305054)
			(end 0.12065 -0.305054)
			(stroke
				(width 0.1)
				(type default)
			)
			(layer "B.Fab")
		)
		(fp_line
			(start 0.67945 0.3048)
			(end 0.67945 -0.305054)
			(stroke
				(width 0.1)
				(type default)
			)
			(layer "B.Fab")
		)
		(pad "1" smd circle
			(at 0.40005 0 180)
			(size 0 0)
			(layers "B.Cu" "B.Mask" "B.Paste")
			(net "P3V3_AUX")
		)
		(pad "2" smd circle
			(at -0.40005 0 180)
			(size 0 0)
			(layers "B.Cu" "B.Mask" "B.Paste")
			(net "PVCCIO_AUX_PLD")
		)
	)
	(footprint ""
		(layer "B.Cu")
		(at 56.94934 -51.95697)
		(property "Reference" "C50"
			(at 0 0 0)
			(layer "B.SilkS")
			(hide yes)
			(effects
				(font
					(size 1.27 1.27)
				)
				(justify mirror)
			)
		)
		(property "Value" ""
			(at 0 0 0)
			(layer "B.Fab")
			(effects
				(font
					(size 1.27 1.27)
				)
				(justify mirror)
			)
		)
		(duplicate_pad_numbers_are_jumpers no)
		(fp_line
			(start -0.7874 -0.4064)
			(end -0.7874 0.4064)
			(stroke
				(width 0.1524)
				(type default)
			)
			(layer "B.SilkS")
		)
		(fp_line
			(start -0.7874 0.4064)
			(end 0.7874 0.4064)
			(stroke
				(width 0.1524)
				(type default)
			)
			(layer "B.SilkS")
		)
		(fp_line
			(start 0.7874 -0.4064)
			(end -0.7874 -0.4064)
			(stroke
				(width 0.1524)
				(type default)
			)
			(layer "B.SilkS")
		)
		(fp_line
			(start 0.7874 0.4064)
			(end 0.7874 -0.4064)
			(stroke
				(width 0.1524)
				(type default)
			)
			(layer "B.SilkS")
		)
		(fp_line
			(start -0.67945 -0.3048)
			(end -0.67945 0.3048)
			(stroke
				(width 0.1)
				(type default)
			)
			(layer "B.Fab")
		)
		(fp_line
			(start -0.67945 0.3048)
			(end -0.120396 0.3048)
			(stroke
				(width 0.1)
				(type default)
			)
			(layer "B.Fab")
		)
		(fp_line
			(start -0.12065 -0.3048)
			(end -0.67945 -0.3048)
			(stroke
				(width 0.1)
				(type default)
			)
			(layer "B.Fab")
		)
		(fp_line
			(start -0.12065 -0.2794)
			(end -0.12065 -0.3048)
			(stroke
				(width 0.1)
				(type default)
			)
			(layer "B.Fab")
		)
		(fp_line
			(start -0.120396 0.2794)
			(end 0.12065 0.2794)
			(stroke
				(width 0.1)
				(type default)
			)
			(layer "B.Fab")
		)
		(fp_line
			(start -0.120396 0.3048)
			(end -0.120396 0.2794)
			(stroke
				(width 0.1)
				(type default)
			)
			(layer "B.Fab")
		)
		(fp_line
			(start 0.12065 -0.305054)
			(end 0.12065 -0.2794)
			(stroke
				(width 0.1)
				(type default)
			)
			(layer "B.Fab")
		)
		(fp_line
			(start 0.12065 -0.2794)
			(end -0.12065 -0.2794)
			(stroke
				(width 0.1)
				(type default)
			)
			(layer "B.Fab")
		)
		(fp_line
			(start 0.12065 0.2794)
			(end 0.12065 0.3048)
			(stroke
				(width 0.1)
				(type default)
			)
			(layer "B.Fab")
		)
		(fp_line
			(start 0.12065 0.3048)
			(end 0.67945 0.3048)
			(stroke
				(width 0.1)
				(type default)
			)
			(layer "B.Fab")
		)
		(fp_line
			(start 0.67945 -0.305054)
			(end 0.12065 -0.305054)
			(stroke
				(width 0.1)
				(type default)
			)
			(layer "B.Fab")
		)
		(fp_line
			(start 0.67945 0.3048)
			(end 0.67945 -0.305054)
			(stroke
				(width 0.1)
				(type default)
			)
			(layer "B.Fab")
		)
		(pad "1" smd circle
			(at 0.40005 0 180)
			(size 0 0)
			(layers "B.Cu" "B.Mask" "B.Paste")
			(net "P1V0_STBY_RC_VCC10A")
		)
		(pad "2" smd circle
			(at -0.40005 0 180)
			(size 0 0)
			(layers "B.Cu" "B.Mask" "B.Paste")
			(net "GND")
		)
	)
	(footprint ""
		(layer "B.Cu")
		(at 49.53 -54.1528 180)
		(property "Reference" "C51"
			(at 0 0 0)
			(layer "B.SilkS")
			(hide yes)
			(effects
				(font
					(size 1.27 1.27)
				)
				(justify mirror)
			)
		)
		(property "Value" ""
			(at 0 0 0)
			(layer "B.Fab")
			(effects
				(font
					(size 1.27 1.27)
				)
				(justify mirror)
			)
		)
		(duplicate_pad_numbers_are_jumpers no)
		(fp_line
			(start 0.7874 0.4064)
			(end 0.7874 -0.4064)
			(stroke
				(width 0.1524)
				(type default)
			)
			(layer "B.SilkS")
		)
		(fp_line
			(start 0.7874 -0.4064)
			(end -0.7874 -0.4064)
			(stroke
				(width 0.1524)
				(type default)
			)
			(layer "B.SilkS")
		)
		(fp_line
			(start -0.7874 0.4064)
			(end 0.7874 0.4064)
			(stroke
				(width 0.1524)
				(type default)
			)
			(layer "B.SilkS")
		)
		(fp_line
			(start -0.7874 -0.4064)
			(end -0.7874 0.4064)
			(stroke
				(width 0.1524)
				(type default)
			)
			(layer "B.SilkS")
		)
		(fp_line
			(start 0.67945 0.3048)
			(end 0.67945 -0.305054)
			(stroke
				(width 0.1)
				(type default)
			)
			(layer "B.Fab")
		)
		(fp_line
			(start 0.67945 -0.305054)
			(end 0.12065 -0.305054)
			(stroke
				(width 0.1)
				(type default)
			)
			(layer "B.Fab")
		)
		(fp_line
			(start 0.12065 0.3048)
			(end 0.67945 0.3048)
			(stroke
				(width 0.1)
				(type default)
			)
			(layer "B.Fab")
		)
		(fp_line
			(start 0.12065 0.2794)
			(end 0.12065 0.3048)
			(stroke
				(width 0.1)
				(type default)
			)
			(layer "B.Fab")
		)
		(fp_line
			(start 0.12065 -0.2794)
			(end -0.12065 -0.2794)
			(stroke
				(width 0.1)
				(type default)
			)
			(layer "B.Fab")
		)
		(fp_line
			(start 0.12065 -0.305054)
			(end 0.12065 -0.2794)
			(stroke
				(width 0.1)
				(type default)
			)
			(layer "B.Fab")
		)
		(fp_line
			(start -0.120396 0.3048)
			(end -0.120396 0.2794)
			(stroke
				(width 0.1)
				(type default)
			)
			(layer "B.Fab")
		)
		(fp_line
			(start -0.120396 0.2794)
			(end 0.12065 0.2794)
			(stroke
				(width 0.1)
				(type default)
			)
			(layer "B.Fab")
		)
		(fp_line
			(start -0.12065 -0.2794)
			(end -0.12065 -0.3048)
			(stroke
				(width 0.1)
				(type default)
			)
			(layer "B.Fab")
		)
		(fp_line
			(start -0.12065 -0.3048)
			(end -0.67945 -0.3048)
			(stroke
				(width 0.1)
				(type default)
			)
			(layer "B.Fab")
		)
		(fp_line
			(start -0.67945 0.3048)
			(end -0.120396 0.3048)
			(stroke
				(width 0.1)
				(type default)
			)
			(layer "B.Fab")
		)
		(fp_line
			(start -0.67945 -0.3048)
			(end -0.67945 0.3048)
			(stroke
				(width 0.1)
				(type default)
			)
			(layer "B.Fab")
		)
		(pad "1" smd circle
			(at 0.40005 0)
			(size 0 0)
			(layers "B.Cu" "B.Mask" "B.Paste")
			(net "P3V3_STBY_DACAV33")
		)
		(pad "2" smd circle
			(at -0.40005 0)
			(size 0 0)
			(layers "B.Cu" "B.Mask" "B.Paste")
			(net "GND")
		)
	)
)
